# T6G (Grand Teton) — schematic netlist excerpt (pin names and nets, part order shuffled) for the footprints in the layout excerpt that follows; sources: Cadence DE-HDL packaged netlist, KiCad conversion of 04192023_DAF0TMB3IC0_F0TG_MB_C_brd_V02_OCP.brd

PR4009  Q_RES  71.5K 1% EMPTY  pkg 0402LF  page 152 : A = P12V_SCM_R ; B = P12V_SCM_OV_FB
R1742  Q_RES  22 1% CHIP  pkg 0402LF  page 171 : A = JTAG_SCM_PLD_R_TDI ; B = JTAG_SCM_PLD_TDI

(kicad_pcb
	(version 20260206)
	(generator "pcbnew")
	(generator_version "10.0")
	(general
		(thickness 1.6)
		(legacy_teardrops no)
	)
	(paper "A4")
	(title_block
		(title "04192023_DAF0TMB3IC0_F0TG_MB_C_brd_V02_OCP.brd")
		(comment 1 "Grand Teton / footprints 1056-1057 of 8354")
	)
	(layers
		(0 "F.Cu" signal "TOP")
		(4 "In1.Cu" signal "GND")
		(6 "In2.Cu" signal "IN1")
		(8 "In3.Cu" signal "GND1")
		(10 "In4.Cu" signal "IN2")
		(12 "In5.Cu" signal "GND2")
		(14 "In6.Cu" signal "IN3")
		(16 "In7.Cu" signal "GND3")
		(18 "In8.Cu" signal "VCC")
		(20 "In9.Cu" signal "VCC1")
		(22 "In10.Cu" signal "GND4")
		(24 "In11.Cu" signal "IN4")
		(26 "In12.Cu" signal "GND5")
		(28 "In13.Cu" signal "IN5")
		(30 "In14.Cu" signal "GND6")
		(32 "In15.Cu" signal "IN6")
		(34 "In16.Cu" signal "GND7")
		(2 "B.Cu" signal "BOTTOM")
		(9 "F.Adhes" user "F.Adhesive")
		(11 "B.Adhes" user "B.Adhesive")
		(13 "F.Paste" user "Package Geometry/Pastemask Top")
		(15 "B.Paste" user "Package Geometry/Pastemask Bottom")
		(5 "F.SilkS" user "Ref Des/Silkscreen Top")
		(7 "B.SilkS" user "Ref Des/Silkscreen Bottom")
		(1 "F.Mask" user "Board Geometry/Soldermask Top")
		(3 "B.Mask" user "Board Geometry/Soldermask Bottom")
		(17 "Dwgs.User" user "User.Drawings")
		(19 "Cmts.User" user "User.Comments")
		(21 "Eco1.User" user "User.Eco1")
		(23 "Eco2.User" user "User.Eco2")
		(25 "Edge.Cuts" user "Board Geometry/Outline")
		(27 "Margin" user)
		(31 "F.CrtYd" user "Package Geometry/Place Bound Top")
		(29 "B.CrtYd" user "Package Geometry/Place Bound Bottom")
		(35 "F.Fab" user "Ref Des/Assembly Top")
		(33 "B.Fab" user "Ref Des/Assembly Bottom")
	)
	(footprint ""
		(layer "F.Cu")
		(at 138.426952 -58.532014)
		(property "Reference" "R1742"
			(at 0 0 0)
			(layer "F.SilkS")
			(hide yes)
			(effects
				(font
					(size 1.27 1.27)
				)
			)
		)
		(property "Value" ""
			(at 0 0 0)
			(layer "F.Fab")
			(effects
				(font
					(size 1.27 1.27)
				)
			)
		)
		(duplicate_pad_numbers_are_jumpers no)
		(fp_line
			(start -0.7874 -0.4064)
			(end 0.7874 -0.4064)
			(stroke
				(width 0.1524)
				(type default)
			)
			(layer "F.SilkS")
		)
		(fp_line
			(start -0.7874 0.4064)
			(end -0.7874 -0.4064)
			(stroke
				(width 0.1524)
				(type default)
			)
			(layer "F.SilkS")
		)
		(fp_line
			(start 0.7874 -0.4064)
			(end 0.7874 0.4064)
			(stroke
				(width 0.1524)
				(type default)
			)
			(layer "F.SilkS")
		)
		(fp_line
			(start 0.7874 0.4064)
			(end -0.7874 0.4064)
			(stroke
				(width 0.1524)
				(type default)
			)
			(layer "F.SilkS")
		)
		(fp_line
			(start -0.67945 -0.305054)
			(end -0.12065 -0.305054)
			(stroke
				(width 0.1)
				(type default)
			)
			(layer "F.Fab")
		)
		(fp_line
			(start -0.67945 0.3048)
			(end -0.67945 -0.305054)
			(stroke
				(width 0.1)
				(type default)
			)
			(layer "F.Fab")
		)
		(fp_line
			(start -0.12065 -0.305054)
			(end -0.12065 -0.2794)
			(stroke
				(width 0.1)
				(type default)
			)
			(layer "F.Fab")
		)
		(fp_line
			(start -0.12065 -0.2794)
			(end 0.12065 -0.2794)
			(stroke
				(width 0.1)
				(type default)
			)
			(layer "F.Fab")
		)
		(fp_line
			(start -0.12065 0.2794)
			(end -0.12065 0.3048)
			(stroke
				(width 0.1)
				(type default)
			)
			(layer "F.Fab")
		)
		(fp_line
			(start -0.12065 0.3048)
			(end -0.67945 0.3048)
			(stroke
				(width 0.1)
				(type default)
			)
			(layer "F.Fab")
		)
		(fp_line
			(start 0.120396 0.2794)
			(end -0.12065 0.2794)
			(stroke
				(width 0.1)
				(type default)
			)
			(layer "F.Fab")
		)
		(fp_line
			(start 0.120396 0.3048)
			(end 0.120396 0.2794)
			(stroke
				(width 0.1)
				(type default)
			)
			(layer "F.Fab")
		)
		(fp_line
			(start 0.12065 -0.3048)
			(end 0.67945 -0.3048)
			(stroke
				(width 0.1)
				(type default)
			)
			(layer "F.Fab")
		)
		(fp_line
			(start 0.12065 -0.2794)
			(end 0.12065 -0.3048)
			(stroke
				(width 0.1)
				(type default)
			)
			(layer "F.Fab")
		)
		(fp_line
			(start 0.67945 -0.3048)
			(end 0.67945 0.3048)
			(stroke
				(width 0.1)
				(type default)
			)
			(layer "F.Fab")
		)
		(fp_line
			(start 0.67945 0.3048)
			(end 0.120396 0.3048)
			(stroke
				(width 0.1)
				(type default)
			)
			(layer "F.Fab")
		)
		(pad "1" smd circle
			(at -0.40005 0)
			(size 0 0)
			(layers "F.Cu" "F.Mask" "F.Paste")
			(net "JTAG_SCM_PLD_R_TDI")
		)
		(pad "2" smd circle
			(at 0.40005 0)
			(size 0 0)
			(layers "F.Cu" "F.Mask" "F.Paste")
			(net "JTAG_SCM_PLD_TDI")
		)
	)
	(footprint ""
		(layer "F.Cu")
		(at 171.664122 -26.84399 90)
		(property "Reference" "PR4009"
			(at 0 0 90)
			(layer "F.SilkS")
			(hide yes)
			(effects
				(font
					(size 1.27 1.27)
				)
			)
		)
		(property "Value" ""
			(at 0 0 90)
			(layer "F.Fab")
			(effects
				(font
					(size 1.27 1.27)
				)
			)
		)
		(duplicate_pad_numbers_are_jumpers no)
		(fp_line
			(start 0.7874 -0.4064)
			(end 0.7874 0.4064)
			(stroke
				(width 0.1524)
				(type default)
			)
			(layer "F.SilkS")
		)
		(fp_line
			(start -0.7874 -0.4064)
			(end 0.7874 -0.4064)
			(stroke
				(width 0.1524)
				(type default)
			)
			(layer "F.SilkS")
		)
		(fp_line
			(start 0.7874 0.4064)
			(end -0.7874 0.4064)
			(stroke
				(width 0.1524)
				(type default)
			)
			(layer "F.SilkS")
		)
		(fp_line
			(start -0.7874 0.4064)
			(end -0.7874 -0.4064)
			(stroke
				(width 0.1524)
				(type default)
			)
			(layer "F.SilkS")
		)
		(fp_line
			(start -0.12065 -0.305054)
			(end -0.12065 -0.2794)
			(stroke
				(width 0.1)
				(type default)
			)
			(layer "F.Fab")
		)
		(fp_line
			(start -0.67945 -0.305054)
			(end -0.12065 -0.305054)
			(stroke
				(width 0.1)
				(type default)
			)
			(layer "F.Fab")
		)
		(fp_line
			(start 0.67945 -0.3048)
			(end 0.67945 0.3048)
			(stroke
				(width 0.1)
				(type default)
			)
			(layer "F.Fab")
		)
		(fp_line
			(start 0.12065 -0.3048)
			(end 0.67945 -0.3048)
			(stroke
				(width 0.1)
				(type default)
			)
			(layer "F.Fab")
		)
		(fp_line
			(start 0.12065 -0.2794)
			(end 0.12065 -0.3048)
			(stroke
				(width 0.1)
				(type default)
			)
			(layer "F.Fab")
		)
		(fp_line
			(start -0.12065 -0.2794)
			(end 0.12065 -0.2794)
			(stroke
				(width 0.1)
				(type default)
			)
			(layer "F.Fab")
		)
		(fp_line
			(start 0.120396 0.2794)
			(end -0.12065 0.2794)
			(stroke
				(width 0.1)
				(type default)
			)
			(layer "F.Fab")
		)
		(fp_line
			(start -0.12065 0.2794)
			(end -0.12065 0.3048)
			(stroke
				(width 0.1)
				(type default)
			)
			(layer "F.Fab")
		)
		(fp_line
			(start 0.67945 0.3048)
			(end 0.120396 0.3048)
			(stroke
				(width 0.1)
				(type default)
			)
			(layer "F.Fab")
		)
		(fp_line
			(start 0.120396 0.3048)
			(end 0.120396 0.2794)
			(stroke
				(width 0.1)
				(type default)
			)
			(layer "F.Fab")
		)
		(fp_line
			(start -0.12065 0.3048)
			(end -0.67945 0.3048)
			(stroke
				(width 0.1)
				(type default)
			)
			(layer "F.Fab")
		)
		(fp_line
			(start -0.67945 0.3048)
			(end -0.67945 -0.305054)
			(stroke
				(width 0.1)
				(type default)
			)
			(layer "F.Fab")
		)
		(pad "1" smd circle
			(at -0.40005 0 90)
			(size 0 0)
			(layers "F.Cu" "F.Mask" "F.Paste")
			(net "P12V_SCM_R")
		)
		(pad "2" smd circle
			(at 0.40005 0 90)
			(size 0 0)
			(layers "F.Cu" "F.Mask" "F.Paste")
			(net "P12V_SCM_OV_FB")
		)
	)
)
